FILE_TYPE=LIBRARY_PARTS;
primitive 'MIC5166','MIC5166_DFN';
  pin
    'EN':
      PIN_NUMBER='(7)';
      INPUT_LOAD='(-0.01,0.01)';
    'VIN':
      PIN_NUMBER='(10)';
      PINUSE='POWER';
      NO_LOAD_CHECK='Both';
      NO_IO_CHECK='Both';
      NO_ASSERT_CHECK='TRUE';
      NO_DIR_CHECK='TRUE';
      ALLOW_CONNECT='TRUE';
    'VREF':
      PIN_NUMBER='(1)';
      OUTPUT_LOAD='(1.0,-1.0)';
    'BIAS':
      PIN_NUMBER='(2)';
      BIDIRECTIONAL='TRUE';
      INPUT_LOAD='(-0.01,0.01)';
      OUTPUT_LOAD='(1.0,-1.0)';
    'AGND':
      PIN_NUMBER='(3)';
      PINUSE='GROUND';
      NO_LOAD_CHECK='Both';
      NO_IO_CHECK='Both';
      NO_ASSERT_CHECK='TRUE';
      NO_DIR_CHECK='TRUE';
      ALLOW_CONNECT='TRUE';
    'PG':
      PIN_NUMBER='(5)';
      OUTPUT_LOAD='(1.0,-1.0)';
    'VDDQ':
      PIN_NUMBER='(4)';
      PINUSE='POWER';
      NO_LOAD_CHECK='Both';
      NO_IO_CHECK='Both';
      NO_ASSERT_CHECK='TRUE';
      NO_DIR_CHECK='TRUE';
      ALLOW_CONNECT='TRUE';
    'SNS':
      PIN_NUMBER='(6)';
      INPUT_LOAD='(-0.01,0.01)';
    'PGND':
      PIN_NUMBER='(8)';
      PINUSE='GROUND';
      NO_LOAD_CHECK='Both';
      NO_IO_CHECK='Both';
      NO_ASSERT_CHECK='TRUE';
      NO_DIR_CHECK='TRUE';
      ALLOW_CONNECT='TRUE';
    'VTT':
      PIN_NUMBER='(9)';
      OUTPUT_LOAD='(1.0,-1.0)';
    'THPAD':
      PIN_NUMBER='(11)';
      PINUSE='GROUND';
      NO_LOAD_CHECK='Both';
      NO_IO_CHECK='Both';
      NO_ASSERT_CHECK='TRUE';
      NO_DIR_CHECK='TRUE';
      ALLOW_CONNECT='TRUE';
  end_pin;
  body
    PART_NAME='MIC5166';
    BODY_NAME='MIC5166';
    PHYS_DES_PREFIX='EU';
  end_body;
end_primitive;

END.
